# BARRELEYE_G2-FPDB_POST-EVT-HW-EBOM-X00_20161123-add_2nd_source_X08-20161215-Final-b.xls — Summary (bom)
| PLATFORM SOURCING AND PSL COMPLIANCE |  |  |  |  |  |  |  |  |  |
| Platform Name: |  |  |  |  |  |  |  |  |  |
| REVISION HISTORY |  |  |  |  |  |  |  |  |  |
| BOM Revision: | ECR # | Revision Description | Originator | Date |  |  |  |  |  |
| Commodity Sourcing | # of components (X00 BOM) | % of Total | # of components (X01 BOM) | % of Total | # of components (X02 BOM) | % of Total | # of components (RTS) | % of Total | Risk Mitigation Plans in Place |
| Sole Source |  |  |  |  |  |  |  |  |  |
| Single Source |  |  |  |  |  |  |  |  |  |
| Multiple |  |  |  |  |  |  |  |  | NA |
| Total |  |  |  |  |  |  |  |  | NA |
|  |  | # of components | # of components aligned with Customer PSL* | % PSL alignment |  |  |  |  |  |
| Class 1 (Customer Managed) |  |  |  |  |  |  |  |  |  |
| Class 2 (ODM Managed to Customer PSL) |  |  |  |  |  |  |  |  |  |
| All other components(ODM Managed to ODM PSL) |  |  |  |  |  |  |  |  |  |
| *RFQ and/or Contract will list requirements for complying with Customer's PSL |  |  |  |  |  |  |  |  |  |
| Reference for quotation |  |  |  |  |  |  |  |  |  |
